# BASEBOARD_FAB2 (Tioga Pass) — schematic netlist excerpt (pin names and nets, part order shuffled) for the footprints in the layout excerpt that follows; sources: Cadence DE-HDL packaged netlist, KiCad conversion of Wiwynn_Tioga_Pass_MB.brd

C3D27  CAP_A  0.1UF 16V 10% EMPTY  pkg 0402V  page 214 : A = VSENSE_PVCCIO_CPU1_SKT_VSEN ; B = VSENSE_PVCCIO_CPU1_SKT_VRTN
R9W12  RES  10.0K 1% CHIP  pkg 0402  page 239 : A = P3V3_STBY ; B = PWRGD_P2V5_BMC_STBY_R
C22W25  SC22U16V5MX-4-GP  20%  pkg SMD-BCG5  page 236 : \1\ = VR_FET_SW_P12V_STBY_PVDDQ_DEF ; \2\ = GND

(kicad_pcb
	(version 20260206)
	(generator "pcbnew")
	(generator_version "10.0")
	(general
		(thickness 1.6)
		(legacy_teardrops no)
	)
	(paper "A4")
	(title_block
		(title "Wiwynn_Tioga_Pass_MB.brd")
		(comment 1 "Tioga Pass / footprints 2231-2233 of 4770")
	)
	(layers
		(0 "F.Cu" signal "TOP")
		(4 "In1.Cu" signal "L2GND")
		(6 "In2.Cu" signal "L3")
		(8 "In3.Cu" signal "L4GND")
		(10 "In4.Cu" signal "L5")
		(12 "In5.Cu" signal "L6GND")
		(14 "In6.Cu" signal "L7VCC")
		(16 "In7.Cu" signal "L8VCC")
		(18 "In8.Cu" signal "L9GND")
		(20 "In9.Cu" signal "L10")
		(22 "In10.Cu" signal "L11GND")
		(24 "In11.Cu" signal "L12")
		(26 "In12.Cu" signal "L13GND")
		(2 "B.Cu" signal "BOTTOM")
		(9 "F.Adhes" user "F.Adhesive")
		(11 "B.Adhes" user "B.Adhesive")
		(13 "F.Paste" user "Package Geometry/Pastemask Top")
		(15 "B.Paste" user "Package Geometry/Pastemask Bottom")
		(5 "F.SilkS" user "Ref Des/Silkscreen Top")
		(7 "B.SilkS" user "Ref Des/Silkscreen Bottom")
		(1 "F.Mask" user "Board Geometry/Soldermask Top")
		(3 "B.Mask" user "Board Geometry/Soldermask Bottom")
		(17 "Dwgs.User" user "User.Drawings")
		(19 "Cmts.User" user "User.Comments")
		(21 "Eco1.User" user "User.Eco1")
		(23 "Eco2.User" user "User.Eco2")
		(25 "Edge.Cuts" user "Board Geometry/Outline")
		(27 "Margin" user)
		(31 "F.CrtYd" user "Package Geometry/Place Bound Top")
		(29 "B.CrtYd" user "Package Geometry/Place Bound Bottom")
		(35 "F.Fab" user "Ref Des/Assembly Top")
		(33 "B.Fab" user "Ref Des/Assembly Bottom")
	)
	(footprint ""
		(layer "F.Cu")
		(at 450.723 -20.2692 -90)
		(property "Reference" "R9W12"
			(at -0.8382 -0.67818 270)
			(unlocked yes)
			(layer "F.SilkS")
			(effects
				(font
					(size 0.4064 0.254)
					(thickness 0.1524)
				)
				(justify left)
			)
		)
		(property "Value" ""
			(at 0 0 270)
			(layer "F.Fab")
			(effects
				(font
					(size 1.27 1.27)
				)
			)
		)
		(duplicate_pad_numbers_are_jumpers no)
		(fp_poly
			(pts
				(xy -0.2794 -0.1016) (xy 0.2794 -0.1016) (xy 0.2794 0.9906) (xy -0.2794 0.9906)
			)
			(stroke
				(width 0)
				(type default)
			)
			(fill no)
			(layer "F.CrtYd")
		)
		(fp_line
			(start -0.2794 0.9906)
			(end 0.2794 0.9906)
			(stroke
				(width 0.1)
				(type default)
			)
			(layer "F.Fab")
		)
		(fp_line
			(start 0.2794 0.9906)
			(end 0.2794 -0.1016)
			(stroke
				(width 0.1)
				(type default)
			)
			(layer "F.Fab")
		)
		(fp_line
			(start -0.2794 -0.1016)
			(end -0.2794 0.9906)
			(stroke
				(width 0.1)
				(type default)
			)
			(layer "F.Fab")
		)
		(fp_line
			(start 0.2794 -0.1016)
			(end -0.2794 -0.1016)
			(stroke
				(width 0.1)
				(type default)
			)
			(layer "F.Fab")
		)
		(pad "1" smd rect
			(at 0 0 270)
			(size 0.508 0.508)
			(layers "F.Cu" "F.Mask" "F.Paste")
			(net "P3V3_STBY")
		)
		(pad "2" smd rect
			(at 0 0.889 270)
			(size 0.508 0.508)
			(layers "F.Cu" "F.Mask" "F.Paste")
			(net "PWRGD_P2V5_BMC_STBY_R")
		)
		(zone
			(layer "F.Cu")
			(hatch none 0.5)
			(connect_pads
				(clearance 0)
			)
			(min_thickness 0.25)
			(keepout
				(tracks not_allowed)
				(vias allowed)
				(pads allowed)
				(copperpour not_allowed)
				(footprints allowed)
			)
			(placement
				(enabled no)
				(sheetname "")
			)
			(fill
				(thermal_gap 0.5)
				(thermal_bridge_width 0.5)
				(island_removal_mode 0)
			)
			(polygon
				(pts
					(xy 450.088 -20.5232) (xy 450.088 -20.0152) (xy 450.469 -20.0152) (xy 450.469 -20.5232)
				)
			)
		)
		(zone
			(layer "F.Cu")
			(hatch none 0.5)
			(connect_pads
				(clearance 0)
			)
			(min_thickness 0.25)
			(keepout
				(tracks allowed)
				(vias not_allowed)
				(pads allowed)
				(copperpour not_allowed)
				(footprints allowed)
			)
			(placement
				(enabled no)
				(sheetname "")
			)
			(fill
				(thermal_gap 0.5)
				(thermal_bridge_width 0.5)
				(island_removal_mode 0)
			)
			(polygon
				(pts
					(xy 450.469 -20.5232) (xy 450.469 -20.0152) (xy 450.088 -20.0152) (xy 450.088 -20.5232)
				)
			)
		)
	)
	(footprint ""
		(layer "F.Cu")
		(at 367.922556 -156.250894 180)
		(property "Reference" "C22W25"
			(at 0 0 180)
			(layer "F.SilkS")
			(hide yes)
			(effects
				(font
					(size 1.27 1.27)
				)
			)
		)
		(property "Value" "*"
			(at -0.0762 -6.2357 180)
			(unlocked yes)
			(layer "F.Fab")
			(hide yes)
			(effects
				(font
					(size 1.27 1.016)
					(thickness 0.1524)
				)
			)
		)
		(property "Device Type" "SC22U16V5MX-4-GP_SMD-BCG5-SC22A"
			(at -0.0762 -8.2677 180)
			(unlocked yes)
			(layer "F.Fab")
			(hide yes)
			(effects
				(font
					(size 1.27 1.016)
					(thickness 0.1524)
				)
			)
		)
		(duplicate_pad_numbers_are_jumpers no)
		(fp_line
			(start 0.635 0)
			(end -0.635 0)
			(stroke
				(width 0.508)
				(type default)
			)
			(layer "F.SilkS")
		)
		(fp_rect
			(start -0.9652 1.778)
			(end 0.9652 -1.778)
			(stroke
				(width 0)
				(type default)
			)
			(fill no)
			(layer "F.CrtYd")
		)
		(fp_poly
			(pts
				(xy -0.9652 -1.778) (xy 0.9652 -1.778) (xy 0.9652 1.778) (xy -0.9652 1.778)
			)
			(stroke
				(width 0)
				(type default)
			)
			(fill no)
			(layer "F.Fab")
		)
		(pad "1" smd rect
			(at 0 -0.9652 180)
			(size 1.397 1.143)
			(layers "F.Cu" "F.Mask" "F.Paste")
			(net "VR_FET_SW_P12V_STBY_PVDDQ_DEF")
		)
		(pad "2" smd rect
			(at 0 0.9652 180)
			(size 1.397 1.143)
			(layers "F.Cu" "F.Mask" "F.Paste")
			(net "GND")
		)
	)
	(footprint ""
		(layer "F.Cu")
		(at 161.6456 -64.897 180)
		(property "Reference" "C3D27"
			(at 0 0 180)
			(layer "F.SilkS")
			(hide yes)
			(effects
				(font
					(size 1.27 1.27)
				)
			)
		)
		(property "Value" ""
			(at 0 0 180)
			(layer "F.Fab")
			(effects
				(font
					(size 1.27 1.27)
				)
			)
		)
		(duplicate_pad_numbers_are_jumpers no)
		(fp_poly
			(pts
				(xy 0.3048 -0.1016) (xy 0.3048 0.9906) (xy -0.3048 0.9906) (xy -0.3048 -0.1016)
			)
			(stroke
				(width 0)
				(type default)
			)
			(fill no)
			(layer "F.CrtYd")
		)
		(fp_line
			(start 0.3048 0.9906)
			(end 0.3048 -0.1016)
			(stroke
				(width 0.1)
				(type default)
			)
			(layer "F.Fab")
		)
		(fp_line
			(start 0.3048 -0.1016)
			(end -0.3048 -0.1016)
			(stroke
				(width 0.1)
				(type default)
			)
			(layer "F.Fab")
		)
		(fp_line
			(start -0.3048 0.9906)
			(end 0.3048 0.9906)
			(stroke
				(width 0.1)
				(type default)
			)
			(layer "F.Fab")
		)
		(fp_line
			(start -0.3048 -0.1016)
			(end -0.3048 0.9906)
			(stroke
				(width 0.1)
				(type default)
			)
			(layer "F.Fab")
		)
		(pad "1" smd rect
			(at 0 0 180)
			(size 0.508 0.508)
			(layers "F.Cu" "F.Mask" "F.Paste")
			(net "VSENSE_PVCCIO_CPU1_SKT_VSEN")
		)
		(pad "2" smd rect
			(at 0 0.889 180)
			(size 0.508 0.508)
			(layers "F.Cu" "F.Mask" "F.Paste")
			(net "VSENSE_PVCCIO_CPU1_SKT_VRTN")
		)
		(zone
			(layer "F.Cu")
			(hatch none 0.5)
			(connect_pads
				(clearance 0)
			)
			(min_thickness 0.25)
			(keepout
				(tracks not_allowed)
				(vias allowed)
				(pads allowed)
				(copperpour not_allowed)
				(footprints allowed)
			)
			(placement
				(enabled no)
				(sheetname "")
			)
			(fill
				(thermal_gap 0.5)
				(thermal_bridge_width 0.5)
				(island_removal_mode 0)
			)
			(polygon
				(pts
					(xy 161.8996 -65.532) (xy 161.3916 -65.532) (xy 161.3916 -65.151) (xy 161.8996 -65.151)
				)
			)
		)
		(zone
			(layer "F.Cu")
			(hatch none 0.5)
			(connect_pads
				(clearance 0)
			)
			(min_thickness 0.25)
			(keepout
				(tracks allowed)
				(vias not_allowed)
				(pads allowed)
				(copperpour not_allowed)
				(footprints allowed)
			)
			(placement
				(enabled no)
				(sheetname "")
			)
			(fill
				(thermal_gap 0.5)
				(thermal_bridge_width 0.5)
				(island_removal_mode 0)
			)
			(polygon
				(pts
					(xy 161.8996 -65.151) (xy 161.3916 -65.151) (xy 161.3916 -65.532) (xy 161.8996 -65.532)
				)
			)
		)
	)
)
